(kicad_pcb
	(version 20241229)
	(generator "pcbnew")
	(generator_version "9.0")
	(general
		(thickness 1.711)
		(legacy_teardrops no)
	)
	(paper "A4")
	(title_block
		(title "Antmicro Baseboard for Jetson AGX Thor")
		(date "2026-02-18")
		(rev "1.1.0")
		(company "Antmicro Ltd")
		(comment 1 "www.antmicro.com")
		(comment 9 "footprints 302-304 of 1170")
	)
	(layers
		(0 "F.Cu" signal)
		(4 "In1.Cu" signal)
		(6 "In2.Cu" signal)
		(8 "In3.Cu" signal)
		(10 "In4.Cu" jumper)
		(12 "In5.Cu" signal)
		(14 "In6.Cu" signal)
		(16 "In7.Cu" signal)
		(18 "In8.Cu" signal)
		(2 "B.Cu" signal)
		(9 "F.Adhes" user "F.Adhesive")
		(11 "B.Adhes" user "B.Adhesive")
		(13 "F.Paste" user)
		(15 "B.Paste" user)
		(5 "F.SilkS" user "F.Silkscreen")
		(7 "B.SilkS" user "B.Silkscreen")
		(1 "F.Mask" user)
		(3 "B.Mask" user)
		(17 "Dwgs.User" user "User.Drawings")
		(19 "Cmts.User" user "User.Comments")
		(21 "Eco1.User" user "User.Eco1")
		(23 "Eco2.User" user "User.Eco2")
		(25 "Edge.Cuts" user)
		(27 "Margin" user)
		(31 "F.CrtYd" user "F.Courtyard")
		(29 "B.CrtYd" user "B.Courtyard")
		(35 "F.Fab" user)
		(33 "B.Fab" user)
	)
	(footprint "antmicro-footprints:C_0402_1005Metric"
		(layer "F.Cu")
		(at 91.1 91.7)
		(descr "Capacitor SMD 0402")
		(tags "capacitor SMD 0402")
		(property "Reference" "C347"
			(at 1.1 0.500001 0)
			(layer "F.SilkS")
			(effects
				(font
					(size 0.7 0.7)
					(thickness 0.15)
				)
				(justify left bottom)
			)
		)
		(property "Value" "C_100n_0402"
			(at -1.022927 2.155213 0)
			(layer "F.Fab")
			(effects
				(font
					(size 0.7 0.7)
					(thickness 0.15)
				)
				(justify left bottom)
			)
		)
		(property "Datasheet" "https://www.murata.com/products/productdetail?partno=GRM155R61H104KE14%23"
			(at 0 0 0)
			(layer "F.Fab")
			(hide yes)
			(effects
				(font
					(size 1.27 1.27)
					(thickness 0.15)
				)
			)
		)
		(property "Description" "SMD Multilayer Ceramic Capacitor, 0.1 µF, 50 V, 0402 [1005 Metric], ± 10%, X5R, GRM Series"
			(at 0 0 0)
			(layer "F.Fab")
			(hide yes)
			(effects
				(font
					(size 1.27 1.27)
					(thickness 0.15)
				)
			)
		)
		(property "Manufacturer" "Murata"
			(at 0 0 0)
			(unlocked yes)
			(layer "F.Fab")
			(hide yes)
			(effects
				(font
					(size 1 1)
					(thickness 0.15)
				)
			)
		)
		(property "MPN" "GRM155R61H104KE14D"
			(at 0 0 0)
			(unlocked yes)
			(layer "F.Fab")
			(hide yes)
			(effects
				(font
					(size 1 1)
					(thickness 0.15)
				)
			)
		)
		(property "Val" "100n"
			(at 0 0 0)
			(unlocked yes)
			(layer "F.Fab")
			(hide yes)
			(effects
				(font
					(size 1 1)
					(thickness 0.15)
				)
			)
		)
		(property "License" "Apache-2.0"
			(at 0 0 0)
			(unlocked yes)
			(layer "F.Fab")
			(hide yes)
			(effects
				(font
					(size 1 1)
					(thickness 0.15)
				)
			)
		)
		(property "Author" "Antmicro"
			(at 0 0 0)
			(unlocked yes)
			(layer "F.Fab")
			(hide yes)
			(effects
				(font
					(size 1 1)
					(thickness 0.15)
				)
			)
		)
		(property "Voltage" "50V"
			(at 0 0 0)
			(unlocked yes)
			(layer "F.Fab")
			(hide yes)
			(effects
				(font
					(size 1 1)
					(thickness 0.15)
				)
			)
		)
		(property "Dielectric" "X5R"
			(at 0 0 0)
			(unlocked yes)
			(layer "F.Fab")
			(hide yes)
			(effects
				(font
					(size 1 1)
					(thickness 0.15)
				)
			)
		)
		(sheetname "/SoM_IO2/")
		(sheetfile "som_io2.kicad_sch")
		(attr smd)
		(fp_rect
			(start -0.925 -0.47)
			(end 0.925 0.47)
			(stroke
				(width 0.05)
				(type default)
			)
			(fill no)
			(layer "F.CrtYd")
		)
		(fp_line
			(start -0.494 -0.25)
			(end 0.504 -0.25)
			(stroke
				(width 0.15)
				(type solid)
			)
			(layer "F.Fab")
		)
		(fp_line
			(start -0.494 0.248)
			(end -0.494 -0.25)
			(stroke
				(width 0.15)
				(type solid)
			)
			(layer "F.Fab")
		)
		(fp_line
			(start 0.504 -0.25)
			(end 0.504 0.248)
			(stroke
				(width 0.15)
				(type solid)
			)
			(layer "F.Fab")
		)
		(fp_line
			(start 0.504 0.248)
			(end -0.494 0.248)
			(stroke
				(width 0.15)
				(type solid)
			)
			(layer "F.Fab")
		)
		(fp_text user "License: Apache-2.0"
			(at -0.939 5.799 0)
			(layer "F.Fab")
			(effects
				(font
					(size 0.7 0.7)
					(thickness 0.15)
				)
				(justify left bottom)
			)
		)
		(fp_text user "${REFERENCE}"
			(at -0.939 4.599 0)
			(layer "F.Fab")
			(effects
				(font
					(size 0.7 0.7)
					(thickness 0.15)
				)
				(justify left bottom)
			)
		)
		(fp_text user "Author: Antmicro"
			(at -0.939 3.399 0)
			(layer "F.Fab")
			(effects
				(font
					(size 0.7 0.7)
					(thickness 0.15)
				)
				(justify left bottom)
			)
		)
		(pad "1" smd roundrect
			(at -0.48 0)
			(size 0.59 0.64)
			(layers "F.Cu" "F.Mask" "F.Paste")
			(roundrect_rratio 0.25)
			(net 648 "/Expansion connector/DP3.TX3+")
			(pintype "passive")
		)
		(pad "2" smd roundrect
			(at 0.48 0)
			(size 0.59 0.64)
			(layers "F.Cu" "F.Mask" "F.Paste")
			(roundrect_rratio 0.25)
			(net 1267 "/SoM_IO2/DP3.TX3_C+")
			(pintype "passive")
		)
	)
	(footprint "antmicro-footprints:C_0402_1005Metric"
		(layer "F.Cu")
		(at 130.549999 60.98)
		(descr "Capacitor SMD 0402")
		(tags "capacitor SMD 0402")
		(property "Reference" "C374"
			(at 0.910001 -0.58 0)
			(layer "F.SilkS")
			(effects
				(font
					(size 0.7 0.7)
					(thickness 0.15)
				)
				(justify left bottom)
			)
		)
		(property "Value" "C_100n_0402"
			(at -1.022927 2.155213 0)
			(layer "F.Fab")
			(effects
				(font
					(size 0.7 0.7)
					(thickness 0.15)
				)
				(justify left bottom)
			)
		)
		(property "Datasheet" "https://www.murata.com/products/productdetail?partno=GRM155R61H104KE14%23"
			(at 0 0 0)
			(layer "F.Fab")
			(hide yes)
			(effects
				(font
					(size 1.27 1.27)
					(thickness 0.15)
				)
			)
		)
		(property "Description" "SMD Multilayer Ceramic Capacitor, 0.1 µF, 50 V, 0402 [1005 Metric], ± 10%, X5R, GRM Series"
			(at 0 0 0)
			(layer "F.Fab")
			(hide yes)
			(effects
				(font
					(size 1.27 1.27)
					(thickness 0.15)
				)
			)
		)
		(property "Manufacturer" "Murata"
			(at 0 0 0)
			(unlocked yes)
			(layer "F.Fab")
			(hide yes)
			(effects
				(font
					(size 1 1)
					(thickness 0.15)
				)
			)
		)
		(property "MPN" "GRM155R61H104KE14D"
			(at 0 0 0)
			(unlocked yes)
			(layer "F.Fab")
			(hide yes)
			(effects
				(font
					(size 1 1)
					(thickness 0.15)
				)
			)
		)
		(property "Val" "100n"
			(at 0 0 0)
			(unlocked yes)
			(layer "F.Fab")
			(hide yes)
			(effects
				(font
					(size 1 1)
					(thickness 0.15)
				)
			)
		)
		(property "License" "Apache-2.0"
			(at 0 0 0)
			(unlocked yes)
			(layer "F.Fab")
			(hide yes)
			(effects
				(font
					(size 1 1)
					(thickness 0.15)
				)
			)
		)
		(property "Author" "Antmicro"
			(at 0 0 0)
			(unlocked yes)
			(layer "F.Fab")
			(hide yes)
			(effects
				(font
					(size 1 1)
					(thickness 0.15)
				)
			)
		)
		(property "Voltage" "50V"
			(at 0 0 0)
			(unlocked yes)
			(layer "F.Fab")
			(hide yes)
			(effects
				(font
					(size 1 1)
					(thickness 0.15)
				)
			)
		)
		(property "Dielectric" "X5R"
			(at 0 0 0)
			(unlocked yes)
			(layer "F.Fab")
			(hide yes)
			(effects
				(font
					(size 1 1)
					(thickness 0.15)
				)
			)
		)
		(sheetname "/DCDC/")
		(sheetfile "dcdc.kicad_sch")
		(attr smd)
		(fp_poly
			(pts
				(xy -0.925 -0.47) (xy -0.925 0.47) (xy 0.925 0.47) (xy 0.925 -0.47)
			)
			(stroke
				(width 0.05)
				(type default)
			)
			(fill no)
			(layer "F.CrtYd")
		)
		(fp_line
			(start -0.494 -0.25)
			(end 0.504 -0.25)
			(stroke
				(width 0.15)
				(type solid)
			)
			(layer "F.Fab")
		)
		(fp_line
			(start -0.494 0.248)
			(end -0.494 -0.25)
			(stroke
				(width 0.15)
				(type solid)
			)
			(layer "F.Fab")
		)
		(fp_line
			(start 0.504 -0.25)
			(end 0.504 0.248)
			(stroke
				(width 0.15)
				(type solid)
			)
			(layer "F.Fab")
		)
		(fp_line
			(start 0.504 0.248)
			(end -0.494 0.248)
			(stroke
				(width 0.15)
				(type solid)
			)
			(layer "F.Fab")
		)
		(fp_text user "License: Apache-2.0"
			(at -0.939 5.799 0)
			(layer "F.Fab")
			(effects
				(font
					(size 0.7 0.7)
					(thickness 0.15)
				)
				(justify left bottom)
			)
		)
		(fp_text user "${REFERENCE}"
			(at -0.939 4.599 0)
			(layer "F.Fab")
			(effects
				(font
					(size 0.7 0.7)
					(thickness 0.15)
				)
				(justify left bottom)
			)
		)
		(fp_text user "Author: Antmicro"
			(at -0.939 3.399 0)
			(layer "F.Fab")
			(effects
				(font
					(size 0.7 0.7)
					(thickness 0.15)
				)
				(justify left bottom)
			)
		)
		(pad "1" smd roundrect
			(at -0.48 0)
			(size 0.59 0.64)
			(layers "F.Cu" "F.Mask" "F.Paste")
			(roundrect_rratio 0.25)
			(net 13 "VCC")
			(pintype "passive")
		)
		(pad "2" smd roundrect
			(at 0.48 0)
			(size 0.59 0.64)
			(layers "F.Cu" "F.Mask" "F.Paste")
			(roundrect_rratio 0.25)
			(net 1 "GND")
			(pintype "passive")
		)
	)
	(footprint "antmicro-footprints:R_0402_1005Metric"
		(layer "F.Cu")
		(at 190.6 82.4)
		(descr "Resistor SMD 0402")
		(tags "resistor SMD 0402")
		(property "Reference" "R107"
			(at -3.78 0.49 0)
			(layer "F.SilkS")
			(effects
				(font
					(size 0.7 0.7)
					(thickness 0.15)
				)
				(justify left bottom)
			)
		)
		(property "Value" "R_4k7_0402"
			(at -1.011843 1.772046 0)
			(layer "F.Fab")
			(effects
				(font
					(size 0.7 0.7)
					(thickness 0.15)
				)
				(justify left bottom)
			)
		)
		(property "Datasheet" "https://www.bourns.com/docs/product-datasheets/cr.pdf"
			(at 0 0 0)
			(layer "F.Fab")
			(hide yes)
			(effects
				(font
					(size 1.27 1.27)
					(thickness 0.15)
				)
			)
		)
		(property "Description" "SMD Chip Resistor, 4.7 kohm, ± 1%, 62.5 mW, 0402 [1005 Metric], Thick Film, General Purpose"
			(at 0 0 0)
			(layer "F.Fab")
			(hide yes)
			(effects
				(font
					(size 1.27 1.27)
					(thickness 0.15)
				)
			)
		)
		(property "Manufacturer" "Bourns"
			(at 0 0 0)
			(unlocked yes)
			(layer "F.Fab")
			(hide yes)
			(effects
				(font
					(size 1 1)
					(thickness 0.15)
				)
			)
		)
		(property "MPN" "CR0402-FX-4701GLF"
			(at 0 0 0)
			(unlocked yes)
			(layer "F.Fab")
			(hide yes)
			(effects
				(font
					(size 1 1)
					(thickness 0.15)
				)
			)
		)
		(property "Val" "4k7"
			(at 0 0 0)
			(unlocked yes)
			(layer "F.Fab")
			(hide yes)
			(effects
				(font
					(size 1 1)
					(thickness 0.15)
				)
			)
		)
		(property "License" "Apache-2.0"
			(at 0 0 0)
			(unlocked yes)
			(layer "F.Fab")
			(hide yes)
			(effects
				(font
					(size 1 1)
					(thickness 0.15)
				)
			)
		)
		(property "Author" "Antmicro"
			(at 0 0 0)
			(unlocked yes)
			(layer "F.Fab")
			(hide yes)
			(effects
				(font
					(size 1 1)
					(thickness 0.15)
				)
			)
		)
		(property "Tolerance" "1%"
			(at 0 0 0)
			(unlocked yes)
			(layer "F.Fab")
			(hide yes)
			(effects
				(font
					(size 1 1)
					(thickness 0.15)
				)
			)
		)
		(sheetname "/USB Debug, PD/")
		(sheetfile "usb_debug_pd.kicad_sch")
		(attr smd)
		(fp_poly
			(pts
				(xy -0.925 -0.47) (xy -0.925 0.47) (xy 0.925 0.47) (xy 0.925 -0.47)
			)
			(stroke
				(width 0.05)
				(type default)
			)
			(fill no)
			(layer "F.CrtYd")
		)
		(fp_poly
			(pts
				(xy -0.5 -0.25) (xy -0.5 0.25) (xy 0.5 0.25) (xy 0.5 -0.25)
			)
			(stroke
				(width 0.15)
				(type solid)
			)
			(fill no)
			(layer "F.Fab")
		)
		(fp_text user "License: Apache-2.0"
			(at -0.949999 5.169 0)
			(layer "F.Fab")
			(effects
				(font
					(size 0.7 0.7)
					(thickness 0.15)
				)
				(justify left bottom)
			)
		)
		(fp_text user "Author: Antmicro"
			(at -0.95 4.169 0)
			(layer "F.Fab")
			(effects
				(font
					(size 0.7 0.7)
					(thickness 0.15)
				)
				(justify left bottom)
			)
		)
		(fp_text user "${REFERENCE}"
			(at -0.95 3.168 0)
			(layer "F.Fab")
			(effects
				(font
					(size 0.7 0.7)
					(thickness 0.15)
				)
				(justify left bottom)
			)
		)
		(pad "1" smd roundrect
			(at -0.48 0)
			(size 0.59 0.64)
			(layers "F.Cu" "F.Mask" "F.Paste")
			(roundrect_rratio 0.25)
			(net 2 "+3V3")
			(pintype "passive")
		)
		(pad "2" smd roundrect
			(at 0.48 0)
			(size 0.59 0.64)
			(layers "F.Cu" "F.Mask" "F.Paste")
			(roundrect_rratio 0.25)
			(net 950 "/USB Debug, PD/PDC_I2C2_SDA")
			(pintype "passive")
		)
	)
)
